(kicad_pcb
	(version 20260206)
	(generator "pcbnew")
	(generator_version "10.0")
	(general
		(thickness 1.6)
		(legacy_teardrops no)
	)
	(paper "A4")
	(title_block
		(title "01162023_DA0F0TEBIF0_F0T_Expander_BD_F_brd_V02_OCP.brd")
		(comment 1 "Grand Teton / footprints 1374-1381 of 9728")
	)
	(layers
		(0 "F.Cu" signal "TOP")
		(4 "In1.Cu" signal "GND")
		(6 "In2.Cu" signal "VCC")
		(8 "In3.Cu" signal "VCC1")
		(10 "In4.Cu" signal "GND1")
		(12 "In5.Cu" signal "IN1")
		(14 "In6.Cu" signal "GND2")
		(16 "In7.Cu" signal "IN2")
		(18 "In8.Cu" signal "GND3")
		(20 "In9.Cu" signal "IN3")
		(22 "In10.Cu" signal "GND4")
		(24 "In11.Cu" signal "IN4")
		(26 "In12.Cu" signal "GND5")
		(28 "In13.Cu" signal "IN5")
		(30 "In14.Cu" signal "GND6")
		(32 "In15.Cu" signal "IN6")
		(34 "In16.Cu" signal "GND7")
		(2 "B.Cu" signal "BOTTOM")
		(9 "F.Adhes" user "F.Adhesive")
		(11 "B.Adhes" user "B.Adhesive")
		(13 "F.Paste" user "Package Geometry/Pastemask Top")
		(15 "B.Paste" user "Package Geometry/Pastemask Bottom")
		(5 "F.SilkS" user "Ref Des/Silkscreen Top")
		(7 "B.SilkS" user "Ref Des/Silkscreen Bottom")
		(1 "F.Mask" user "Board Geometry/Soldermask Top")
		(3 "B.Mask" user "Board Geometry/Soldermask Bottom")
		(17 "Dwgs.User" user "User.Drawings")
		(19 "Cmts.User" user "User.Comments")
		(21 "Eco1.User" user "User.Eco1")
		(23 "Eco2.User" user "User.Eco2")
		(25 "Edge.Cuts" user "Board Geometry/Outline")
		(27 "Margin" user)
		(31 "F.CrtYd" user "Package Geometry/Place Bound Top")
		(29 "B.CrtYd" user "Package Geometry/Place Bound Bottom")
		(35 "F.Fab" user "Ref Des/Assembly Top")
		(33 "B.Fab" user "Ref Des/Assembly Bottom")
	)
	(footprint ""
		(layer "F.Cu")
		(at 205.101698 -304.036476 90)
		(property "Reference" "R1314"
			(at 0 0 90)
			(layer "F.SilkS")
			(hide yes)
			(effects
				(font
					(size 1.27 1.27)
				)
			)
		)
		(property "Value" ""
			(at 0 0 90)
			(layer "F.Fab")
			(effects
				(font
					(size 1.27 1.27)
				)
			)
		)
		(duplicate_pad_numbers_are_jumpers no)
		(fp_line
			(start 0.7874 -0.4064)
			(end 0.7874 0.4064)
			(stroke
				(width 0.1524)
				(type default)
			)
			(layer "F.SilkS")
		)
		(fp_line
			(start -0.7874 -0.4064)
			(end 0.7874 -0.4064)
			(stroke
				(width 0.1524)
				(type default)
			)
			(layer "F.SilkS")
		)
		(fp_line
			(start 0.7874 0.4064)
			(end -0.7874 0.4064)
			(stroke
				(width 0.1524)
				(type default)
			)
			(layer "F.SilkS")
		)
		(fp_line
			(start -0.7874 0.4064)
			(end -0.7874 -0.4064)
			(stroke
				(width 0.1524)
				(type default)
			)
			(layer "F.SilkS")
		)
		(fp_line
			(start -0.12065 -0.305054)
			(end -0.12065 -0.2794)
			(stroke
				(width 0.1)
				(type default)
			)
			(layer "F.Fab")
		)
		(fp_line
			(start -0.67945 -0.305054)
			(end -0.12065 -0.305054)
			(stroke
				(width 0.1)
				(type default)
			)
			(layer "F.Fab")
		)
		(fp_line
			(start 0.67945 -0.3048)
			(end 0.67945 0.3048)
			(stroke
				(width 0.1)
				(type default)
			)
			(layer "F.Fab")
		)
		(fp_line
			(start 0.12065 -0.3048)
			(end 0.67945 -0.3048)
			(stroke
				(width 0.1)
				(type default)
			)
			(layer "F.Fab")
		)
		(fp_line
			(start 0.12065 -0.2794)
			(end 0.12065 -0.3048)
			(stroke
				(width 0.1)
				(type default)
			)
			(layer "F.Fab")
		)
		(fp_line
			(start -0.12065 -0.2794)
			(end 0.12065 -0.2794)
			(stroke
				(width 0.1)
				(type default)
			)
			(layer "F.Fab")
		)
		(fp_line
			(start 0.120396 0.2794)
			(end -0.12065 0.2794)
			(stroke
				(width 0.1)
				(type default)
			)
			(layer "F.Fab")
		)
		(fp_line
			(start -0.12065 0.2794)
			(end -0.12065 0.3048)
			(stroke
				(width 0.1)
				(type default)
			)
			(layer "F.Fab")
		)
		(fp_line
			(start 0.67945 0.3048)
			(end 0.120396 0.3048)
			(stroke
				(width 0.1)
				(type default)
			)
			(layer "F.Fab")
		)
		(fp_line
			(start 0.120396 0.3048)
			(end 0.120396 0.2794)
			(stroke
				(width 0.1)
				(type default)
			)
			(layer "F.Fab")
		)
		(fp_line
			(start -0.12065 0.3048)
			(end -0.67945 0.3048)
			(stroke
				(width 0.1)
				(type default)
			)
			(layer "F.Fab")
		)
		(fp_line
			(start -0.67945 0.3048)
			(end -0.67945 -0.305054)
			(stroke
				(width 0.1)
				(type default)
			)
			(layer "F.Fab")
		)
		(pad "1" smd circle
			(at -0.40005 0 90)
			(size 0 0)
			(layers "F.Cu" "F.Mask" "F.Paste")
			(net "GND")
		)
		(pad "2" smd circle
			(at 0.40005 0 90)
			(size 0 0)
			(layers "F.Cu" "F.Mask" "F.Paste")
			(net "PEX1_SPARE4")
		)
	)
	(footprint ""
		(layer "F.Cu")
		(at 107.323128 -279.486868 -90)
		(property "Reference" "PR102"
			(at 0 0 270)
			(layer "F.SilkS")
			(hide yes)
			(effects
				(font
					(size 1.27 1.27)
				)
			)
		)
		(property "Value" ""
			(at 0 0 270)
			(layer "F.Fab")
			(effects
				(font
					(size 1.27 1.27)
				)
			)
		)
		(duplicate_pad_numbers_are_jumpers no)
		(fp_line
			(start -0.7874 0.4064)
			(end -0.7874 -0.4064)
			(stroke
				(width 0.1524)
				(type default)
			)
			(layer "F.SilkS")
		)
		(fp_line
			(start 0.7874 0.4064)
			(end -0.7874 0.4064)
			(stroke
				(width 0.1524)
				(type default)
			)
			(layer "F.SilkS")
		)
		(fp_line
			(start -0.7874 -0.4064)
			(end 0.7874 -0.4064)
			(stroke
				(width 0.1524)
				(type default)
			)
			(layer "F.SilkS")
		)
		(fp_line
			(start 0.7874 -0.4064)
			(end 0.7874 0.4064)
			(stroke
				(width 0.1524)
				(type default)
			)
			(layer "F.SilkS")
		)
		(fp_line
			(start -0.67945 0.3048)
			(end -0.67945 -0.305054)
			(stroke
				(width 0.1)
				(type default)
			)
			(layer "F.Fab")
		)
		(fp_line
			(start -0.12065 0.3048)
			(end -0.67945 0.3048)
			(stroke
				(width 0.1)
				(type default)
			)
			(layer "F.Fab")
		)
		(fp_line
			(start 0.120396 0.3048)
			(end 0.120396 0.2794)
			(stroke
				(width 0.1)
				(type default)
			)
			(layer "F.Fab")
		)
		(fp_line
			(start 0.67945 0.3048)
			(end 0.120396 0.3048)
			(stroke
				(width 0.1)
				(type default)
			)
			(layer "F.Fab")
		)
		(fp_line
			(start -0.12065 0.2794)
			(end -0.12065 0.3048)
			(stroke
				(width 0.1)
				(type default)
			)
			(layer "F.Fab")
		)
		(fp_line
			(start 0.120396 0.2794)
			(end -0.12065 0.2794)
			(stroke
				(width 0.1)
				(type default)
			)
			(layer "F.Fab")
		)
		(fp_line
			(start -0.12065 -0.2794)
			(end 0.12065 -0.2794)
			(stroke
				(width 0.1)
				(type default)
			)
			(layer "F.Fab")
		)
		(fp_line
			(start 0.12065 -0.2794)
			(end 0.12065 -0.3048)
			(stroke
				(width 0.1)
				(type default)
			)
			(layer "F.Fab")
		)
		(fp_line
			(start 0.12065 -0.3048)
			(end 0.67945 -0.3048)
			(stroke
				(width 0.1)
				(type default)
			)
			(layer "F.Fab")
		)
		(fp_line
			(start 0.67945 -0.3048)
			(end 0.67945 0.3048)
			(stroke
				(width 0.1)
				(type default)
			)
			(layer "F.Fab")
		)
		(fp_line
			(start -0.67945 -0.305054)
			(end -0.12065 -0.305054)
			(stroke
				(width 0.1)
				(type default)
			)
			(layer "F.Fab")
		)
		(fp_line
			(start -0.12065 -0.305054)
			(end -0.12065 -0.2794)
			(stroke
				(width 0.1)
				(type default)
			)
			(layer "F.Fab")
		)
		(pad "1" smd circle
			(at -0.40005 0 270)
			(size 0 0)
			(layers "F.Cu" "F.Mask" "F.Paste")
			(net "P0V8_PEX0_LSET1")
		)
		(pad "2" smd circle
			(at 0.40005 0 270)
			(size 0 0)
			(layers "F.Cu" "F.Mask" "F.Paste")
			(net "GND")
		)
	)
	(footprint ""
		(layer "F.Cu")
		(at 30.901894 -32.849312 90)
		(property "Reference" "R5650"
			(at 0 0 90)
			(layer "F.SilkS")
			(hide yes)
			(effects
				(font
					(size 1.27 1.27)
				)
			)
		)
		(property "Value" ""
			(at 0 0 90)
			(layer "F.Fab")
			(effects
				(font
					(size 1.27 1.27)
				)
			)
		)
		(duplicate_pad_numbers_are_jumpers no)
		(fp_line
			(start 0.7874 -0.4064)
			(end 0.7874 0.4064)
			(stroke
				(width 0.1524)
				(type default)
			)
			(layer "F.SilkS")
		)
		(fp_line
			(start -0.7874 -0.4064)
			(end 0.7874 -0.4064)
			(stroke
				(width 0.1524)
				(type default)
			)
			(layer "F.SilkS")
		)
		(fp_line
			(start 0.7874 0.4064)
			(end -0.7874 0.4064)
			(stroke
				(width 0.1524)
				(type default)
			)
			(layer "F.SilkS")
		)
		(fp_line
			(start -0.7874 0.4064)
			(end -0.7874 -0.4064)
			(stroke
				(width 0.1524)
				(type default)
			)
			(layer "F.SilkS")
		)
		(fp_line
			(start -0.12065 -0.305054)
			(end -0.12065 -0.2794)
			(stroke
				(width 0.1)
				(type default)
			)
			(layer "F.Fab")
		)
		(fp_line
			(start -0.67945 -0.305054)
			(end -0.12065 -0.305054)
			(stroke
				(width 0.1)
				(type default)
			)
			(layer "F.Fab")
		)
		(fp_line
			(start 0.67945 -0.3048)
			(end 0.67945 0.3048)
			(stroke
				(width 0.1)
				(type default)
			)
			(layer "F.Fab")
		)
		(fp_line
			(start 0.12065 -0.3048)
			(end 0.67945 -0.3048)
			(stroke
				(width 0.1)
				(type default)
			)
			(layer "F.Fab")
		)
		(fp_line
			(start 0.12065 -0.2794)
			(end 0.12065 -0.3048)
			(stroke
				(width 0.1)
				(type default)
			)
			(layer "F.Fab")
		)
		(fp_line
			(start -0.12065 -0.2794)
			(end 0.12065 -0.2794)
			(stroke
				(width 0.1)
				(type default)
			)
			(layer "F.Fab")
		)
		(fp_line
			(start 0.120396 0.2794)
			(end -0.12065 0.2794)
			(stroke
				(width 0.1)
				(type default)
			)
			(layer "F.Fab")
		)
		(fp_line
			(start -0.12065 0.2794)
			(end -0.12065 0.3048)
			(stroke
				(width 0.1)
				(type default)
			)
			(layer "F.Fab")
		)
		(fp_line
			(start 0.67945 0.3048)
			(end 0.120396 0.3048)
			(stroke
				(width 0.1)
				(type default)
			)
			(layer "F.Fab")
		)
		(fp_line
			(start 0.120396 0.3048)
			(end 0.120396 0.2794)
			(stroke
				(width 0.1)
				(type default)
			)
			(layer "F.Fab")
		)
		(fp_line
			(start -0.12065 0.3048)
			(end -0.67945 0.3048)
			(stroke
				(width 0.1)
				(type default)
			)
			(layer "F.Fab")
		)
		(fp_line
			(start -0.67945 0.3048)
			(end -0.67945 -0.305054)
			(stroke
				(width 0.1)
				(type default)
			)
			(layer "F.Fab")
		)
		(pad "1" smd circle
			(at -0.40005 0 90)
			(size 0 0)
			(layers "F.Cu" "F.Mask" "F.Paste")
			(net "RST_SMB_SSD1_ISO_R_N")
		)
		(pad "2" smd circle
			(at 0.40005 0 90)
			(size 0 0)
			(layers "F.Cu" "F.Mask" "F.Paste")
			(net "RST_SMB_SSD1_ISO_N")
		)
	)
	(footprint ""
		(layer "F.Cu")
		(at 196.119242 -142.590266 180)
		(property "Reference" "C227"
			(at 0 0 180)
			(layer "F.SilkS")
			(hide yes)
			(effects
				(font
					(size 1.27 1.27)
				)
			)
		)
		(property "Value" ""
			(at 0 0 180)
			(layer "F.Fab")
			(effects
				(font
					(size 1.27 1.27)
				)
			)
		)
		(duplicate_pad_numbers_are_jumpers no)
		(fp_line
			(start 0.299974 0.150114)
			(end -0.299974 0.150114)
			(stroke
				(width 0.1)
				(type default)
			)
			(layer "F.Fab")
		)
		(fp_line
			(start 0.299974 -0.150114)
			(end 0.299974 0.150114)
			(stroke
				(width 0.1)
				(type default)
			)
			(layer "F.Fab")
		)
		(fp_line
			(start -0.299974 0.150114)
			(end -0.299974 -0.150114)
			(stroke
				(width 0.1)
				(type default)
			)
			(layer "F.Fab")
		)
		(fp_line
			(start -0.299974 -0.150114)
			(end 0.299974 -0.150114)
			(stroke
				(width 0.1)
				(type default)
			)
			(layer "F.Fab")
		)
		(pad "1" smd rect
			(at -0.2667 0 180)
			(size 0.3048 0.381)
			(layers "F.Cu" "F.Mask" "F.Paste")
			(net "P5E_PEX1_STN0_TX_DN<8>")
		)
		(pad "2" smd rect
			(at 0.2667 0 180)
			(size 0.3048 0.381)
			(layers "F.Cu" "F.Mask" "F.Paste")
			(net "P5E_PEX1_STN0_TX_C_DN<8>")
		)
	)
	(footprint ""
		(layer "F.Cu")
		(at 332.33614 -95.264224 -90)
		(property "Reference" "C2856"
			(at 0 0 270)
			(layer "F.SilkS")
			(hide yes)
			(effects
				(font
					(size 1.27 1.27)
				)
			)
		)
		(property "Value" ""
			(at 0 0 270)
			(layer "F.Fab")
			(effects
				(font
					(size 1.27 1.27)
				)
			)
		)
		(duplicate_pad_numbers_are_jumpers no)
		(fp_line
			(start -0.7874 0.4064)
			(end -0.7874 -0.4064)
			(stroke
				(width 0.1524)
				(type default)
			)
			(layer "F.SilkS")
		)
		(fp_line
			(start 0.7874 0.4064)
			(end -0.7874 0.4064)
			(stroke
				(width 0.1524)
				(type default)
			)
			(layer "F.SilkS")
		)
		(fp_line
			(start -0.7874 -0.4064)
			(end 0.7874 -0.4064)
			(stroke
				(width 0.1524)
				(type default)
			)
			(layer "F.SilkS")
		)
		(fp_line
			(start 0.7874 -0.4064)
			(end 0.7874 0.4064)
			(stroke
				(width 0.1524)
				(type default)
			)
			(layer "F.SilkS")
		)
		(fp_line
			(start -0.67945 0.3048)
			(end -0.67945 -0.305054)
			(stroke
				(width 0.1)
				(type default)
			)
			(layer "F.Fab")
		)
		(fp_line
			(start -0.12065 0.3048)
			(end -0.67945 0.3048)
			(stroke
				(width 0.1)
				(type default)
			)
			(layer "F.Fab")
		)
		(fp_line
			(start 0.120396 0.3048)
			(end 0.120396 0.2794)
			(stroke
				(width 0.1)
				(type default)
			)
			(layer "F.Fab")
		)
		(fp_line
			(start 0.67945 0.3048)
			(end 0.120396 0.3048)
			(stroke
				(width 0.1)
				(type default)
			)
			(layer "F.Fab")
		)
		(fp_line
			(start -0.12065 0.2794)
			(end -0.12065 0.3048)
			(stroke
				(width 0.1)
				(type default)
			)
			(layer "F.Fab")
		)
		(fp_line
			(start 0.120396 0.2794)
			(end -0.12065 0.2794)
			(stroke
				(width 0.1)
				(type default)
			)
			(layer "F.Fab")
		)
		(fp_line
			(start -0.12065 -0.2794)
			(end 0.12065 -0.2794)
			(stroke
				(width 0.1)
				(type default)
			)
			(layer "F.Fab")
		)
		(fp_line
			(start 0.12065 -0.2794)
			(end 0.12065 -0.3048)
			(stroke
				(width 0.1)
				(type default)
			)
			(layer "F.Fab")
		)
		(fp_line
			(start 0.12065 -0.3048)
			(end 0.67945 -0.3048)
			(stroke
				(width 0.1)
				(type default)
			)
			(layer "F.Fab")
		)
		(fp_line
			(start 0.67945 -0.3048)
			(end 0.67945 0.3048)
			(stroke
				(width 0.1)
				(type default)
			)
			(layer "F.Fab")
		)
		(fp_line
			(start -0.67945 -0.305054)
			(end -0.12065 -0.305054)
			(stroke
				(width 0.1)
				(type default)
			)
			(layer "F.Fab")
		)
		(fp_line
			(start -0.12065 -0.305054)
			(end -0.12065 -0.2794)
			(stroke
				(width 0.1)
				(type default)
			)
			(layer "F.Fab")
		)
		(pad "1" smd circle
			(at -0.40005 0 270)
			(size 0 0)
			(layers "F.Cu" "F.Mask" "F.Paste")
			(net "P12V_NIC5_EN_R")
		)
		(pad "2" smd circle
			(at 0.40005 0 270)
			(size 0 0)
			(layers "F.Cu" "F.Mask" "F.Paste")
			(net "GND")
		)
	)
	(footprint ""
		(layer "F.Cu")
		(at 20.771104 -145.189956 180)
		(property "Reference" "R690"
			(at 0 0 180)
			(layer "F.SilkS")
			(hide yes)
			(effects
				(font
					(size 1.27 1.27)
				)
			)
		)
		(property "Value" ""
			(at 0 0 180)
			(layer "F.Fab")
			(effects
				(font
					(size 1.27 1.27)
				)
			)
		)
		(duplicate_pad_numbers_are_jumpers no)
		(fp_line
			(start 0.7874 0.4064)
			(end -0.7874 0.4064)
			(stroke
				(width 0.1524)
				(type default)
			)
			(layer "F.SilkS")
		)
		(fp_line
			(start 0.7874 -0.4064)
			(end 0.7874 0.4064)
			(stroke
				(width 0.1524)
				(type default)
			)
			(layer "F.SilkS")
		)
		(fp_line
			(start -0.7874 0.4064)
			(end -0.7874 -0.4064)
			(stroke
				(width 0.1524)
				(type default)
			)
			(layer "F.SilkS")
		)
		(fp_line
			(start -0.7874 -0.4064)
			(end 0.7874 -0.4064)
			(stroke
				(width 0.1524)
				(type default)
			)
			(layer "F.SilkS")
		)
		(fp_line
			(start 0.67945 0.3048)
			(end 0.120396 0.3048)
			(stroke
				(width 0.1)
				(type default)
			)
			(layer "F.Fab")
		)
		(fp_line
			(start 0.67945 -0.3048)
			(end 0.67945 0.3048)
			(stroke
				(width 0.1)
				(type default)
			)
			(layer "F.Fab")
		)
		(fp_line
			(start 0.12065 -0.2794)
			(end 0.12065 -0.3048)
			(stroke
				(width 0.1)
				(type default)
			)
			(layer "F.Fab")
		)
		(fp_line
			(start 0.12065 -0.3048)
			(end 0.67945 -0.3048)
			(stroke
				(width 0.1)
				(type default)
			)
			(layer "F.Fab")
		)
		(fp_line
			(start 0.120396 0.3048)
			(end 0.120396 0.2794)
			(stroke
				(width 0.1)
				(type default)
			)
			(layer "F.Fab")
		)
		(fp_line
			(start 0.120396 0.2794)
			(end -0.12065 0.2794)
			(stroke
				(width 0.1)
				(type default)
			)
			(layer "F.Fab")
		)
		(fp_line
			(start -0.12065 0.3048)
			(end -0.67945 0.3048)
			(stroke
				(width 0.1)
				(type default)
			)
			(layer "F.Fab")
		)
		(fp_line
			(start -0.12065 0.2794)
			(end -0.12065 0.3048)
			(stroke
				(width 0.1)
				(type default)
			)
			(layer "F.Fab")
		)
		(fp_line
			(start -0.12065 -0.2794)
			(end 0.12065 -0.2794)
			(stroke
				(width 0.1)
				(type default)
			)
			(layer "F.Fab")
		)
		(fp_line
			(start -0.12065 -0.305054)
			(end -0.12065 -0.2794)
			(stroke
				(width 0.1)
				(type default)
			)
			(layer "F.Fab")
		)
		(fp_line
			(start -0.67945 0.3048)
			(end -0.67945 -0.305054)
			(stroke
				(width 0.1)
				(type default)
			)
			(layer "F.Fab")
		)
		(fp_line
			(start -0.67945 -0.305054)
			(end -0.12065 -0.305054)
			(stroke
				(width 0.1)
				(type default)
			)
			(layer "F.Fab")
		)
		(pad "1" smd circle
			(at -0.40005 0 180)
			(size 0 0)
			(layers "F.Cu" "F.Mask" "F.Paste")
			(net "P12V_NIC0")
		)
		(pad "2" smd circle
			(at 0.40005 0 180)
			(size 0 0)
			(layers "F.Cu" "F.Mask" "F.Paste")
			(net "P12V_NIC0_VIN_N")
		)
	)
	(footprint ""
		(layer "F.Cu")
		(at 106.964734 -237.306612 90)
		(property "Reference" "PC292"
			(at 0 0 90)
			(layer "F.SilkS")
			(hide yes)
			(effects
				(font
					(size 1.27 1.27)
				)
			)
		)
		(property "Value" ""
			(at 0 0 90)
			(layer "F.Fab")
			(effects
				(font
					(size 1.27 1.27)
				)
			)
		)
		(duplicate_pad_numbers_are_jumpers no)
		(fp_line
			(start 1.524 -0.762)
			(end 1.524 0.762)
			(stroke
				(width 0.1524)
				(type default)
			)
			(layer "F.SilkS")
		)
		(fp_line
			(start -1.524 -0.762)
			(end 1.524 -0.762)
			(stroke
				(width 0.1524)
				(type default)
			)
			(layer "F.SilkS")
		)
		(fp_line
			(start 1.524 0.762)
			(end -1.524 0.762)
			(stroke
				(width 0.1524)
				(type default)
			)
			(layer "F.SilkS")
		)
		(fp_line
			(start -1.524 0.762)
			(end -1.524 -0.762)
			(stroke
				(width 0.1524)
				(type default)
			)
			(layer "F.SilkS")
		)
		(fp_line
			(start 1.1049 -0.724916)
			(end -1.1049 -0.724916)
			(stroke
				(width 0.1)
				(type default)
			)
			(layer "F.Fab")
		)
		(fp_line
			(start -1.1049 -0.724916)
			(end -1.1049 0.724916)
			(stroke
				(width 0.1)
				(type default)
			)
			(layer "F.Fab")
		)
		(fp_line
			(start 1.1049 0.724916)
			(end 1.1049 -0.724916)
			(stroke
				(width 0.1)
				(type default)
			)
			(layer "F.Fab")
		)
		(fp_line
			(start -1.1049 0.724916)
			(end 1.1049 0.724916)
			(stroke
				(width 0.1)
				(type default)
			)
			(layer "F.Fab")
		)
		(pad "1" smd rect
			(at -0.889 0 270)
			(size 1.016 1.27)
			(layers "F.Cu" "F.Mask" "F.Paste")
			(net "P1V8_PEX_R")
		)
		(pad "2" smd rect
			(at 0.889 0 270)
			(size 1.016 1.27)
			(layers "F.Cu" "F.Mask" "F.Paste")
			(net "GND")
		)
	)
	(footprint ""
		(layer "F.Cu")
		(at 46.434502 -30.94609 180)
		(property "Reference" "C77"
			(at 0 0 180)
			(layer "F.SilkS")
			(hide yes)
			(effects
				(font
					(size 1.27 1.27)
				)
			)
		)
		(property "Value" ""
			(at 0 0 180)
			(layer "F.Fab")
			(effects
				(font
					(size 1.27 1.27)
				)
			)
		)
		(duplicate_pad_numbers_are_jumpers no)
		(fp_line
			(start 0.299974 0.150114)
			(end -0.299974 0.150114)
			(stroke
				(width 0.1)
				(type default)
			)
			(layer "F.Fab")
		)
		(fp_line
			(start 0.299974 -0.150114)
			(end 0.299974 0.150114)
			(stroke
				(width 0.1)
				(type default)
			)
			(layer "F.Fab")
		)
		(fp_line
			(start -0.299974 0.150114)
			(end -0.299974 -0.150114)
			(stroke
				(width 0.1)
				(type default)
			)
			(layer "F.Fab")
		)
		(fp_line
			(start -0.299974 -0.150114)
			(end 0.299974 -0.150114)
			(stroke
				(width 0.1)
				(type default)
			)
			(layer "F.Fab")
		)
		(pad "1" smd rect
			(at -0.2667 0 180)
			(size 0.3048 0.381)
			(layers "F.Cu" "F.Mask" "F.Paste")
			(net "P5E_PEX0_STN2_TX_DP<41>")
		)
		(pad "2" smd rect
			(at 0.2667 0 180)
			(size 0.3048 0.381)
			(layers "F.Cu" "F.Mask" "F.Paste")
			(net "P5E_PEX0_STN2_TX_C_DP<41>")
		)
	)
)
